(kicad_pcb
	(version 20241229)
	(generator "pcbnew")
	(generator_version "9.0")
	(general
		(thickness 1.294)
		(legacy_teardrops no)
	)
	(paper "A3")
	(title_block
		(title "Kintex 410T devboard")
		(date "2024-04-03")
		(rev "1.1.2")
		(comment 9 "footprints 533-538 of 975")
	)
	(layers
		(0 "F.Cu" mixed)
		(4 "In1.Cu" power)
		(6 "In2.Cu" power)
		(8 "In3.Cu" mixed)
		(10 "In4.Cu" power)
		(12 "In5.Cu" mixed)
		(14 "In6.Cu" power)
		(16 "In7.Cu" mixed)
		(18 "In8.Cu" power)
		(2 "B.Cu" mixed)
		(9 "F.Adhes" user "F.Adhesive")
		(11 "B.Adhes" user "B.Adhesive")
		(13 "F.Paste" user)
		(15 "B.Paste" user)
		(5 "F.SilkS" user "F.Silkscreen")
		(7 "B.SilkS" user "B.Silkscreen")
		(1 "F.Mask" user)
		(3 "B.Mask" user)
		(17 "Dwgs.User" user "User.Drawings")
		(19 "Cmts.User" user "User.Comments")
		(21 "Eco1.User" user "User.Eco1")
		(23 "Eco2.User" user "User.Eco2")
		(25 "Edge.Cuts" user)
		(27 "Margin" user)
		(31 "F.CrtYd" user "F.Courtyard")
		(29 "B.CrtYd" user "B.Courtyard")
		(35 "F.Fab" user)
		(33 "B.Fab" user)
	)
	(footprint "antmicro-footprints:C_0402_1005Metric"
		(layer "B.Cu")
		(at 242.2 117.2 90)
		(descr "Capacitor SMD 0402")
		(tags "capacitor SMD 0402")
		(property "Reference" "C213"
			(at -1.45 1.35 90)
			(layer "B.SilkS")
			(effects
				(font
					(size 0.7 0.7)
					(thickness 0.15)
				)
				(justify right bottom mirror)
			)
		)
		(property "Value" "C_1u_0402"
			(at 0 -1.4 90)
			(layer "B.Fab")
			(effects
				(font
					(size 0.7 0.7)
					(thickness 0.15)
				)
				(justify right bottom mirror)
			)
		)
		(property "Description" "SMD Multilayer Ceramic Capacitor, 1 µF, 10 V, 0402 [1005 Metric], ± 10%, X6S, C"
			(at 0 0 90)
			(layer "F.Fab")
			(hide yes)
			(effects
				(font
					(size 1.27 1.27)
					(thickness 0.15)
				)
			)
		)
		(property "Author" "Antmicro"
			(at 359.4 -125 0)
			(layer "B.Fab")
			(hide yes)
			(effects
				(font
					(size 1 1)
					(thickness 0.15)
				)
				(justify mirror)
			)
		)
		(property "DNP" "DNP"
			(at 359.4 -125 0)
			(layer "B.Fab")
			(hide yes)
			(effects
				(font
					(size 1 1)
					(thickness 0.15)
				)
				(justify mirror)
			)
		)
		(property "Dielectric" ""
			(at 359.4 -125 0)
			(layer "B.Fab")
			(hide yes)
			(effects
				(font
					(size 1 1)
					(thickness 0.15)
				)
				(justify mirror)
			)
		)
		(property "License" "Apache-2.0"
			(at 359.4 -125 0)
			(layer "B.Fab")
			(hide yes)
			(effects
				(font
					(size 1 1)
					(thickness 0.15)
				)
				(justify mirror)
			)
		)
		(property "MPN" "C1005X6S1A105K050BC"
			(at 359.4 -125 0)
			(layer "B.Fab")
			(hide yes)
			(effects
				(font
					(size 1 1)
					(thickness 0.15)
				)
				(justify mirror)
			)
		)
		(property "Manufacturer" "TDK"
			(at 359.4 -125 0)
			(layer "B.Fab")
			(hide yes)
			(effects
				(font
					(size 1 1)
					(thickness 0.15)
				)
				(justify mirror)
			)
		)
		(property "Val" "1u"
			(at 359.4 -125 0)
			(layer "B.Fab")
			(hide yes)
			(effects
				(font
					(size 1 1)
					(thickness 0.15)
				)
				(justify mirror)
			)
		)
		(property "Voltage" ""
			(at 359.4 -125 0)
			(layer "B.Fab")
			(hide yes)
			(effects
				(font
					(size 1 1)
					(thickness 0.15)
				)
				(justify mirror)
			)
		)
		(property "dnp" ""
			(at 359.4 -125 0)
			(layer "B.Fab")
			(hide yes)
			(effects
				(font
					(size 1 1)
					(thickness 0.15)
				)
				(justify mirror)
			)
		)
		(property "exclude_from_bom" ""
			(at 359.4 -125 0)
			(layer "B.Fab")
			(hide yes)
			(effects
				(font
					(size 1 1)
					(thickness 0.15)
				)
				(justify mirror)
			)
		)
		(sheetname "User GPIO + LED + button + DIP switch")
		(sheetfile "user-gpio.kicad_sch")
		(attr smd exclude_from_bom)
		(fp_rect
			(start -0.925 0.47)
			(end 0.925 -0.47)
			(stroke
				(width 0.05)
				(type default)
			)
			(fill no)
			(layer "B.CrtYd")
		)
		(fp_line
			(start 0.504 -0.248)
			(end -0.494 -0.248)
			(stroke
				(width 0.15)
				(type solid)
			)
			(layer "B.Fab")
		)
		(fp_line
			(start -0.494 -0.248)
			(end -0.494 0.25)
			(stroke
				(width 0.15)
				(type solid)
			)
			(layer "B.Fab")
		)
		(fp_line
			(start 0.504 0.25)
			(end 0.504 -0.248)
			(stroke
				(width 0.15)
				(type solid)
			)
			(layer "B.Fab")
		)
		(fp_line
			(start -0.494 0.25)
			(end 0.504 0.25)
			(stroke
				(width 0.15)
				(type solid)
			)
			(layer "B.Fab")
		)
		(pad "1" smd roundrect
			(at -0.48 0 90)
			(size 0.59 0.64)
			(layers "B.Cu" "B.Mask" "B.Paste")
			(roundrect_rratio 0.25)
			(net 1 "GND")
			(pintype "passive")
		)
		(pad "2" smd roundrect
			(at 0.48 0 90)
			(size 0.59 0.64)
			(layers "B.Cu" "B.Mask" "B.Paste")
			(roundrect_rratio 0.25)
			(net 703 "+5V")
			(pintype "passive")
		)
	)
	(footprint "antmicro-footprints:R_0402_1005Metric"
		(layer "B.Cu")
		(at 248.801 174.4 90)
		(descr "Resistor SMD 0402")
		(tags "resistor SMD 0402")
		(property "Reference" "R55"
			(at 1.075 -0.551 270)
			(layer "B.SilkS")
			(effects
				(font
					(size 0.7 0.7)
					(thickness 0.15)
				)
				(justify left bottom mirror)
			)
		)
		(property "Value" "R_24k9_0402"
			(at 0 -1.4 270)
			(layer "B.Fab")
			(effects
				(font
					(size 0.7 0.7)
					(thickness 0.15)
				)
				(justify left bottom mirror)
			)
		)
		(property "Description" "SMD Chip Resistor, 24.9 kohm, ± 1%, 63 mW, 0402 [1005 Metric], Thick Film, General Purpose"
			(at 0 0 90)
			(layer "F.Fab")
			(hide yes)
			(effects
				(font
					(size 1.27 1.27)
					(thickness 0.15)
				)
			)
		)
		(property "Author" "Antmicro"
			(at 423.201 -74.401 0)
			(layer "B.Fab")
			(hide yes)
			(effects
				(font
					(size 1 1)
					(thickness 0.15)
				)
				(justify mirror)
			)
		)
		(property "License" "Apache-2.0"
			(at 423.201 -74.401 0)
			(layer "B.Fab")
			(hide yes)
			(effects
				(font
					(size 1 1)
					(thickness 0.15)
				)
				(justify mirror)
			)
		)
		(property "MPN" "CR0402-FX-2492GLF"
			(at 423.201 -74.401 0)
			(layer "B.Fab")
			(hide yes)
			(effects
				(font
					(size 1 1)
					(thickness 0.15)
				)
				(justify mirror)
			)
		)
		(property "Manufacturer" "Bourns"
			(at 423.201 -74.401 0)
			(layer "B.Fab")
			(hide yes)
			(effects
				(font
					(size 1 1)
					(thickness 0.15)
				)
				(justify mirror)
			)
		)
		(property "Tolerance" "1%"
			(at 423.201 -74.401 0)
			(layer "B.Fab")
			(hide yes)
			(effects
				(font
					(size 1 1)
					(thickness 0.15)
				)
				(justify mirror)
			)
		)
		(property "Val" "24k9"
			(at 423.201 -74.401 0)
			(layer "B.Fab")
			(hide yes)
			(effects
				(font
					(size 1 1)
					(thickness 0.15)
				)
				(justify mirror)
			)
		)
		(sheetname "Power supply")
		(sheetfile "power-supply.kicad_sch")
		(attr smd)
		(fp_rect
			(start -0.925 0.47)
			(end 0.925 -0.47)
			(stroke
				(width 0.05)
				(type default)
			)
			(fill no)
			(layer "B.CrtYd")
		)
		(fp_rect
			(start -0.5 0.25)
			(end 0.5 -0.25)
			(stroke
				(width 0.15)
				(type solid)
			)
			(fill no)
			(layer "B.Fab")
		)
		(pad "1" smd roundrect
			(at -0.48 0 90)
			(size 0.59 0.64)
			(layers "B.Cu" "B.Mask" "B.Paste")
			(roundrect_rratio 0.25)
			(net 887 "/Power supply/DEN")
			(pintype "passive")
		)
		(pad "2" smd roundrect
			(at 0.48 0 90)
			(size 0.59 0.64)
			(layers "B.Cu" "B.Mask" "B.Paste")
			(roundrect_rratio 0.25)
			(net 698 "/Power supply/VDD")
			(pintype "passive")
		)
	)
	(footprint "antmicro-footprints:R_0402_1005Metric"
		(layer "B.Cu")
		(at 172.75 175.7125)
		(descr "Resistor SMD 0402")
		(tags "resistor SMD 0402")
		(property "Reference" "R316"
			(at -0.75 0.4125 180)
			(layer "B.SilkS")
			(effects
				(font
					(size 0.7 0.7)
					(thickness 0.15)
				)
				(justify left bottom mirror)
			)
		)
		(property "Value" "R_0R_0402"
			(at 0 -1.4 180)
			(layer "B.Fab")
			(effects
				(font
					(size 0.7 0.7)
					(thickness 0.15)
				)
				(justify left bottom mirror)
			)
		)
		(property "Description" "SMD Chip Resistor, Jumper, 0 ohm, 100 mW, 0402 [1005 Metric], Thick Film, General Purpose"
			(at 0 0 0)
			(layer "F.Fab")
			(hide yes)
			(effects
				(font
					(size 1.27 1.27)
					(thickness 0.15)
				)
			)
		)
		(property "Author" "Antmicro"
			(at 0 0 0)
			(layer "B.Fab")
			(hide yes)
			(effects
				(font
					(size 1 1)
					(thickness 0.15)
				)
				(justify mirror)
			)
		)
		(property "Current" "1A"
			(at 0 0 0)
			(layer "B.Fab")
			(hide yes)
			(effects
				(font
					(size 1 1)
					(thickness 0.15)
				)
				(justify mirror)
			)
		)
		(property "DNP" "DNP"
			(at 0 0 0)
			(layer "B.Fab")
			(hide yes)
			(effects
				(font
					(size 1 1)
					(thickness 0.15)
				)
				(justify mirror)
			)
		)
		(property "License" "Apache-2.0"
			(at 0 0 0)
			(layer "B.Fab")
			(hide yes)
			(effects
				(font
					(size 1 1)
					(thickness 0.15)
				)
				(justify mirror)
			)
		)
		(property "MPN" "ERJ2GE0R00X"
			(at 0 0 0)
			(layer "B.Fab")
			(hide yes)
			(effects
				(font
					(size 1 1)
					(thickness 0.15)
				)
				(justify mirror)
			)
		)
		(property "Manufacturer" "Panasonic"
			(at 0 0 0)
			(layer "B.Fab")
			(hide yes)
			(effects
				(font
					(size 1 1)
					(thickness 0.15)
				)
				(justify mirror)
			)
		)
		(property "Tolerance" ""
			(at 0 0 0)
			(layer "B.Fab")
			(hide yes)
			(effects
				(font
					(size 1 1)
					(thickness 0.15)
				)
				(justify mirror)
			)
		)
		(property "Val" "0R"
			(at 0 0 0)
			(layer "B.Fab")
			(hide yes)
			(effects
				(font
					(size 1 1)
					(thickness 0.15)
				)
				(justify mirror)
			)
		)
		(property "dnp" ""
			(at 0 0 0)
			(layer "B.Fab")
			(hide yes)
			(effects
				(font
					(size 1 1)
					(thickness 0.15)
				)
				(justify mirror)
			)
		)
		(property "exclude_from_bom" ""
			(at 0 0 0)
			(layer "B.Fab")
			(hide yes)
			(effects
				(font
					(size 1 1)
					(thickness 0.15)
				)
				(justify mirror)
			)
		)
		(sheetname "DC-DC Converters")
		(sheetfile "dc-dc.kicad_sch")
		(attr smd exclude_from_bom)
		(fp_rect
			(start -0.925 0.47)
			(end 0.925 -0.47)
			(stroke
				(width 0.05)
				(type default)
			)
			(fill no)
			(layer "B.CrtYd")
		)
		(fp_rect
			(start -0.5 0.25)
			(end 0.5 -0.25)
			(stroke
				(width 0.15)
				(type solid)
			)
			(fill no)
			(layer "B.Fab")
		)
		(pad "1" smd roundrect
			(at -0.48 0)
			(size 0.59 0.64)
			(layers "B.Cu" "B.Mask" "B.Paste")
			(roundrect_rratio 0.25)
			(net 1215 "/DC-DC Converters/SENSE_1V35_N")
			(pintype "passive")
		)
		(pad "2" smd roundrect
			(at 0.48 0)
			(size 0.59 0.64)
			(layers "B.Cu" "B.Mask" "B.Paste")
			(roundrect_rratio 0.25)
			(net 965 "/DC-DC Converters/FB8")
			(pintype "passive")
		)
	)
	(footprint "antmicro-footprints:R_0402_1005Metric"
		(layer "B.Cu")
		(at 163.905001 79.930001 90)
		(descr "Resistor SMD 0402")
		(tags "resistor SMD 0402")
		(property "Reference" "R266"
			(at 1.355001 -0.505001 270)
			(layer "B.SilkS")
			(effects
				(font
					(size 0.7 0.7)
					(thickness 0.15)
				)
				(justify left bottom mirror)
			)
		)
		(property "Value" "R_10k_0402"
			(at 0 -1.4 270)
			(layer "B.Fab")
			(effects
				(font
					(size 0.7 0.7)
					(thickness 0.15)
				)
				(justify left bottom mirror)
			)
		)
		(property "Description" "SMD Chip Resistor, 10 kohm, ± 1%, 62.5 mW, 0402 [1005 Metric], Thick Film, General Purpose"
			(at 0 0 90)
			(layer "F.Fab")
			(hide yes)
			(effects
				(font
					(size 1.27 1.27)
					(thickness 0.15)
				)
			)
		)
		(property "Author" "Antmicro"
			(at 243.835002 -83.975 0)
			(layer "B.Fab")
			(hide yes)
			(effects
				(font
					(size 1 1)
					(thickness 0.15)
				)
				(justify mirror)
			)
		)
		(property "License" "Apache-2.0"
			(at 243.835002 -83.975 0)
			(layer "B.Fab")
			(hide yes)
			(effects
				(font
					(size 1 1)
					(thickness 0.15)
				)
				(justify mirror)
			)
		)
		(property "MPN" "CR0402-FX-1002GLF"
			(at 243.835002 -83.975 0)
			(layer "B.Fab")
			(hide yes)
			(effects
				(font
					(size 1 1)
					(thickness 0.15)
				)
				(justify mirror)
			)
		)
		(property "Manufacturer" "Bourns"
			(at 243.835002 -83.975 0)
			(layer "B.Fab")
			(hide yes)
			(effects
				(font
					(size 1 1)
					(thickness 0.15)
				)
				(justify mirror)
			)
		)
		(property "Tolerance" "1%"
			(at 243.835002 -83.975 0)
			(layer "B.Fab")
			(hide yes)
			(effects
				(font
					(size 1 1)
					(thickness 0.15)
				)
				(justify mirror)
			)
		)
		(property "Val" "10k"
			(at 243.835002 -83.975 0)
			(layer "B.Fab")
			(hide yes)
			(effects
				(font
					(size 1 1)
					(thickness 0.15)
				)
				(justify mirror)
			)
		)
		(sheetname "FMC+ HSPC")
		(sheetfile "fmc-hspc.kicad_sch")
		(attr smd)
		(fp_rect
			(start -0.925 0.47)
			(end 0.925 -0.47)
			(stroke
				(width 0.05)
				(type default)
			)
			(fill no)
			(layer "B.CrtYd")
		)
		(fp_rect
			(start -0.5 0.25)
			(end 0.5 -0.25)
			(stroke
				(width 0.15)
				(type solid)
			)
			(fill no)
			(layer "B.Fab")
		)
		(pad "1" smd roundrect
			(at -0.48 0 90)
			(size 0.59 0.64)
			(layers "B.Cu" "B.Mask" "B.Paste")
			(roundrect_rratio 0.25)
			(net 99 "Net-(J18B-PG_C2M)")
			(pintype "passive")
		)
		(pad "2" smd roundrect
			(at 0.48 0 90)
			(size 0.59 0.64)
			(layers "B.Cu" "B.Mask" "B.Paste")
			(roundrect_rratio 0.25)
			(net 24 "+3V3")
			(pintype "passive")
		)
	)
	(footprint "antmicro-footprints:C_0201"
		(layer "B.Cu")
		(at 188.000001 118.500001 180)
		(descr "Capacitor SMD 0201")
		(tags "capacitor SMD 0201")
		(property "Reference" "C146"
			(at 2.350001 -0.374999 0)
			(layer "B.SilkS")
			(effects
				(font
					(size 0.7 0.7)
					(thickness 0.15)
				)
				(justify left bottom mirror)
			)
		)
		(property "Value" "C_100n_0201"
			(at 0 -1.4 0)
			(layer "B.Fab")
			(effects
				(font
					(size 0.7 0.7)
					(thickness 0.15)
				)
				(justify left bottom mirror)
			)
		)
		(property "Description" "SMD Multilayer Ceramic Capacitor, 0.1 µF, 6.3 V, 0201 [0603 Metric], ± 10%, X6S, CC Series"
			(at 0 0 180)
			(layer "F.Fab")
			(hide yes)
			(effects
				(font
					(size 1.27 1.27)
					(thickness 0.15)
				)
			)
		)
		(property "Author" "Antmicro"
			(at 376.000002 237.000002 0)
			(layer "B.Fab")
			(hide yes)
			(effects
				(font
					(size 1 1)
					(thickness 0.15)
				)
				(justify mirror)
			)
		)
		(property "Dielectric" ""
			(at 376.000002 237.000002 0)
			(layer "B.Fab")
			(hide yes)
			(effects
				(font
					(size 1 1)
					(thickness 0.15)
				)
				(justify mirror)
			)
		)
		(property "License" "Apache-2.0"
			(at 376.000002 237.000002 0)
			(layer "B.Fab")
			(hide yes)
			(effects
				(font
					(size 1 1)
					(thickness 0.15)
				)
				(justify mirror)
			)
		)
		(property "MPN" "CC0201KRX6S5BB104"
			(at 376.000002 237.000002 0)
			(layer "B.Fab")
			(hide yes)
			(effects
				(font
					(size 1 1)
					(thickness 0.15)
				)
				(justify mirror)
			)
		)
		(property "Manufacturer" "YAGEO"
			(at 376.000002 237.000002 0)
			(layer "B.Fab")
			(hide yes)
			(effects
				(font
					(size 1 1)
					(thickness 0.15)
				)
				(justify mirror)
			)
		)
		(property "Val" "100n"
			(at 376.000002 237.000002 0)
			(layer "B.Fab")
			(hide yes)
			(effects
				(font
					(size 1 1)
					(thickness 0.15)
				)
				(justify mirror)
			)
		)
		(property "Voltage" ""
			(at 376.000002 237.000002 0)
			(layer "B.Fab")
			(hide yes)
			(effects
				(font
					(size 1 1)
					(thickness 0.15)
				)
				(justify mirror)
			)
		)
		(sheetname "FPGA supply")
		(sheetfile "fpga-supply.kicad_sch")
		(attr smd)
		(fp_rect
			(start -0.7 0.35)
			(end 0.7 -0.35)
			(stroke
				(width 0.05)
				(type default)
			)
			(fill no)
			(layer "B.CrtYd")
		)
		(fp_rect
			(start 0.3 -0.15)
			(end -0.301 0.149)
			(stroke
				(width 0.15)
				(type solid)
			)
			(fill no)
			(layer "B.Fab")
		)
		(pad "" smd roundrect
			(at -0.349 0.002 180)
			(size 0.318 0.36)
			(layers "B.Paste")
			(roundrect_rratio 0.25)
		)
		(pad "" smd roundrect
			(at 0.341 0.002 180)
			(size 0.318 0.36)
			(layers "B.Paste")
			(roundrect_rratio 0.25)
		)
		(pad "1" smd roundrect
			(at -0.321 0.002 180)
			(size 0.46 0.4)
			(layers "B.Cu" "B.Mask")
			(roundrect_rratio 0.25)
			(net 1 "GND")
			(pintype "passive")
		)
		(pad "2" smd roundrect
			(at 0.32 0.002 180)
			(size 0.46 0.4)
			(layers "B.Cu" "B.Mask")
			(roundrect_rratio 0.25)
			(net 8 "+1V2_MGTAVTT")
			(pintype "passive")
		)
	)
	(footprint "antmicro-footprints:C_0603_1608Metric"
		(layer "B.Cu")
		(at 183 138.26 135)
		(descr "Capacitor SMD 0603")
		(tags "capacitor 0603")
		(property "Reference" "C109"
			(at -1.52028 0.636396 315)
			(unlocked yes)
			(layer "B.SilkS")
			(effects
				(font
					(size 0.7 0.7)
					(thickness 0.15)
				)
				(justify left bottom mirror)
			)
		)
		(property "Value" "C_47u_0603"
			(at 0 -1.6 315)
			(layer "B.Fab")
			(effects
				(font
					(size 0.7 0.7)
					(thickness 0.15)
				)
				(justify left bottom mirror)
			)
		)
		(property "Description" "SMD Multilayer Ceramic Capacitor, 47 µF, 6.3 V, 0603 [1608 Metric], ± 20%, X5R, GRM Series"
			(at 0 0 135)
			(layer "F.Fab")
			(hide yes)
			(effects
				(font
					(size 1.27 1.27)
					(thickness 0.15)
				)
			)
		)
		(property "Author" "Antmicro"
			(at 410.165125 106.624043 0)
			(layer "B.Fab")
			(hide yes)
			(effects
				(font
					(size 1 1)
					(thickness 0.15)
				)
				(justify mirror)
			)
		)
		(property "Dielectric" ""
			(at 410.165125 106.624043 0)
			(layer "B.Fab")
			(hide yes)
			(effects
				(font
					(size 1 1)
					(thickness 0.15)
				)
				(justify mirror)
			)
		)
		(property "License" "Apache-2.0"
			(at 410.165125 106.624043 0)
			(layer "B.Fab")
			(hide yes)
			(effects
				(font
					(size 1 1)
					(thickness 0.15)
				)
				(justify mirror)
			)
		)
		(property "MPN" "GRM188R60J476ME15D"
			(at 410.165125 106.624043 0)
			(layer "B.Fab")
			(hide yes)
			(effects
				(font
					(size 1 1)
					(thickness 0.15)
				)
				(justify mirror)
			)
		)
		(property "Manufacturer" "Murata"
			(at 410.165125 106.624043 0)
			(layer "B.Fab")
			(hide yes)
			(effects
				(font
					(size 1 1)
					(thickness 0.15)
				)
				(justify mirror)
			)
		)
		(property "Val" "47u"
			(at 410.165125 106.624043 0)
			(layer "B.Fab")
			(hide yes)
			(effects
				(font
					(size 1 1)
					(thickness 0.15)
				)
				(justify mirror)
			)
		)
		(property "Voltage" ""
			(at 410.165125 106.624043 0)
			(layer "B.Fab")
			(hide yes)
			(effects
				(font
					(size 1 1)
					(thickness 0.15)
				)
				(justify mirror)
			)
		)
		(sheetname "FPGA Bank 33 & 34")
		(sheetfile "fpga-bank-33-34.kicad_sch")
		(attr smd)
		(fp_line
			(start -0.15 -0.4)
			(end 0.15 -0.4)
			(stroke
				(width 0.15)
				(type solid)
			)
			(layer "B.SilkS")
		)
		(fp_line
			(start -0.15 0.4)
			(end 0.15 0.4)
			(stroke
				(width 0.15)
				(type solid)
			)
			(layer "B.SilkS")
		)
		(fp_poly
			(pts
				(xy -1.25 0.65) (xy 1.25 0.65) (xy 1.25 -0.65) (xy -1.25 -0.65)
			)
			(stroke
				(width 0.05)
				(type solid)
			)
			(fill no)
			(layer "B.CrtYd")
		)
		(fp_poly
			(pts
				(xy -0.8 0.4) (xy 0.8 0.4) (xy 0.8 -0.4) (xy -0.8 -0.4)
			)
			(stroke
				(width 0.15)
				(type solid)
			)
			(fill no)
			(layer "B.Fab")
		)
		(pad "1" smd roundrect
			(at -0.7 0 135)
			(size 0.8 1)
			(layers "B.Cu" "B.Mask" "B.Paste")
			(roundrect_rratio 0.2)
			(net 25 "+1V35")
			(pintype "passive")
		)
		(pad "2" smd roundrect
			(at 0.7 0 135)
			(size 0.8 1)
			(layers "B.Cu" "B.Mask" "B.Paste")
			(roundrect_rratio 0.2)
			(net 1 "GND")
			(pintype "passive")
		)
	)
)
